G04*
G04 #@! TF.GenerationSoftware,Altium Limited,Altium Designer,23.0.1 (38)*
G04*
G04 Layer_Color=32768*
%FSLAX25Y25*%
%MOIN*%
G70*
G04*
G04 #@! TF.SameCoordinates,C48E81DB-6E20-4E2D-80E6-7C5AFAA1A21F*
G04*
G04*
G04 #@! TF.FilePolarity,Positive*
G04*
G01*
G75*
%ADD15C,0.00787*%
D15*
X684350Y-24213D02*
X687303D01*
X684350Y-30906D02*
Y-24213D01*
Y-30906D02*
X687303D01*
Y-24213D01*
X549193Y-235433D02*
X581516D01*
Y-254331D02*
Y-235433D01*
X549193Y-254331D02*
X581516D01*
X549193D02*
Y-235433D01*
X596348Y-262354D02*
X629636D01*
Y-289614D02*
Y-262354D01*
X596348Y-289614D02*
X629636D01*
X596348D02*
Y-262354D01*
X682141Y-324552D02*
X690300D01*
X682141D02*
Y-320330D01*
X690300D01*
Y-324552D02*
Y-320330D01*
X667913Y-325689D02*
X677756D01*
X667913D02*
Y-320768D01*
X677756D01*
Y-325689D02*
Y-320768D01*
X667913Y-318209D02*
X677756D01*
X667913D02*
Y-313287D01*
X677756D01*
Y-318209D02*
Y-313287D01*
X682141Y-317859D02*
X690300D01*
X682141D02*
Y-313637D01*
X690300D01*
Y-317859D02*
Y-313637D01*
X678346Y-108169D02*
X708169D01*
Y-69784D01*
X678346D02*
X708169D01*
X678346Y-108169D02*
Y-69784D01*
X678543Y-61360D02*
X692323D01*
Y-44940D01*
X678543D02*
X692323D01*
X678543Y-61360D02*
Y-44940D01*
X668389Y-96342D02*
X676493D01*
X668389Y-111532D02*
Y-96342D01*
Y-111532D02*
X676493D01*
Y-96342D01*
X667072Y-112106D02*
Y-109153D01*
X661275D02*
X667072D01*
X661275Y-112106D02*
Y-109153D01*
Y-112106D02*
X667072D01*
X690724Y-67716D02*
Y-64567D01*
Y-67716D02*
X696677D01*
Y-64567D01*
X690724D02*
X696677D01*
X673130Y-96358D02*
Y-92618D01*
X666240D02*
X673130D01*
X666240Y-96358D02*
Y-92618D01*
Y-96358D02*
X673130D01*
X677658Y-35335D02*
X681398D01*
Y-28445D01*
X677658D02*
X681398D01*
X677658Y-35335D02*
Y-28445D01*
X685039Y-40772D02*
X688189D01*
Y-34819D01*
X685039D02*
X688189D01*
X685039Y-40772D02*
Y-34819D01*
X692520Y-40908D02*
X695669D01*
Y-34954D01*
X692520D02*
X695669D01*
X692520Y-40908D02*
Y-34954D01*
X612992Y-98032D02*
Y-88583D01*
Y-98032D02*
X621260D01*
Y-88583D01*
X612992D02*
X621260D01*
X624582Y-94882D02*
Y-91732D01*
Y-94882D02*
X630536D01*
Y-91732D01*
X624582D02*
X630536D01*
X580118Y-98032D02*
Y-88583D01*
Y-98032D02*
X588386D01*
Y-88583D01*
X580118D02*
X588386D01*
X595669Y-95103D02*
X598819D01*
Y-89149D01*
X595669D02*
X598819D01*
X595669Y-95103D02*
Y-89149D01*
X415413Y-139764D02*
Y-109843D01*
Y-139764D02*
X431831D01*
Y-109843D01*
X415413D02*
X431831D01*
X407382Y-125000D02*
X412303D01*
X407382Y-134843D02*
Y-125000D01*
Y-134843D02*
X412303D01*
Y-125000D01*
X434154Y-124606D02*
X439075D01*
X434154Y-134449D02*
Y-124606D01*
Y-134449D02*
X439075D01*
Y-124606D01*
X243701Y-125394D02*
X253150D01*
Y-117126D01*
X243701D02*
X253150D01*
X243701Y-125394D02*
Y-117126D01*
X248819Y-113607D02*
X251969D01*
Y-107653D01*
X248819D02*
X251969D01*
X248819Y-113607D02*
Y-107653D01*
X407619Y-113707D02*
X411841D01*
X407619Y-121866D02*
Y-113707D01*
Y-121866D02*
X411841D01*
Y-113707D01*
X434503Y-114810D02*
X438725D01*
X434503Y-122969D02*
Y-114810D01*
Y-122969D02*
X438725D01*
Y-114810D01*
X547023Y-281496D02*
X552977D01*
X547023D02*
Y-278346D01*
X552977D01*
Y-281496D02*
Y-278346D01*
X599892Y-229378D02*
Y-202118D01*
Y-229378D02*
X633179D01*
Y-202118D01*
X599892D02*
X633179D01*
X650787Y-167303D02*
X669685D01*
X650787Y-199626D02*
Y-167303D01*
Y-199626D02*
X669685D01*
Y-167303D01*
X681250Y-189259D02*
X685473D01*
Y-181100D01*
X681250D02*
X685473D01*
X681250Y-189259D02*
Y-181100D01*
X625000Y-237008D02*
Y-230709D01*
Y-237008D02*
X636417D01*
Y-230709D01*
X625000D02*
X636417D01*
X648032Y-220276D02*
X652756D01*
X648032Y-229331D02*
Y-220276D01*
Y-229331D02*
X652756D01*
Y-220276D01*
X565497Y-223765D02*
Y-219542D01*
X557338D02*
X565497D01*
X557338Y-223765D02*
Y-219542D01*
Y-223765D02*
X565497D01*
X594237Y-238878D02*
Y-235925D01*
X588440D02*
X594237D01*
X588440Y-238878D02*
Y-235925D01*
Y-238878D02*
X594237D01*
X596260Y-234449D02*
X602165D01*
X596260Y-245079D02*
Y-234449D01*
Y-245079D02*
X602165D01*
Y-234449D01*
X622244Y-236417D02*
Y-230512D01*
X611614D02*
X622244D01*
X611614Y-236417D02*
Y-230512D01*
Y-236417D02*
X622244D01*
X680315Y-204246D02*
X683465D01*
X680315Y-210199D02*
Y-204246D01*
Y-210199D02*
X683465D01*
Y-204246D01*
X671654Y-193701D02*
X679528D01*
Y-175591D01*
X671654D02*
X679528D01*
X671654Y-193701D02*
Y-175591D01*
X664818Y-203401D02*
X669040D01*
X664818Y-211560D02*
Y-203401D01*
Y-211560D02*
X669040D01*
Y-203401D01*
X683366Y-239173D02*
Y-217520D01*
X655217D02*
X683366D01*
X655217Y-239173D02*
Y-217520D01*
Y-239173D02*
X683366D01*
X633484Y-200787D02*
Y-181890D01*
X601161D02*
X633484D01*
X601161Y-200787D02*
Y-181890D01*
Y-200787D02*
X633484D01*
X592126Y-196272D02*
X600000D01*
Y-180893D01*
X592126D02*
X600000D01*
X592126Y-196272D02*
Y-180893D01*
X672047Y-202953D02*
X676772D01*
X672047Y-212008D02*
Y-202953D01*
Y-212008D02*
X676772D01*
Y-202953D01*
X582677Y-196272D02*
X590551D01*
Y-180893D01*
X582677D02*
X590551D01*
X582677Y-196272D02*
Y-180893D01*
X558366Y-196161D02*
X562106D01*
X558366Y-203051D02*
Y-196161D01*
Y-203051D02*
X562106D01*
Y-196161D01*
X551432Y-227308D02*
X555654D01*
Y-219149D01*
X551432D02*
X555654D01*
X551432Y-227308D02*
Y-219149D01*
X561024Y-217544D02*
X564173D01*
Y-211590D01*
X561024D02*
X564173D01*
X561024Y-217544D02*
Y-211590D01*
X583366Y-150768D02*
Y-117736D01*
X608760D01*
Y-150768D02*
Y-117736D01*
X583366Y-150768D02*
X608760D01*
X616194Y-155839D02*
Y-115551D01*
X700294D01*
Y-155839D02*
Y-115551D01*
X616194Y-155839D02*
X700294D01*
X583071Y-181929D02*
Y-156653D01*
X546850D02*
X583071D01*
X546850Y-181929D02*
Y-156653D01*
Y-181929D02*
X583071D01*
X613976Y-299213D02*
Y-292913D01*
Y-299213D02*
X625394D01*
Y-292913D01*
X613976D02*
X625394D01*
X605709Y-298622D02*
Y-292717D01*
X595079D02*
X605709D01*
X595079Y-298622D02*
Y-292717D01*
Y-298622D02*
X605709D01*
X564054Y-294631D02*
Y-290408D01*
X555894D02*
X564054D01*
X555894Y-294631D02*
Y-290408D01*
Y-294631D02*
X564054D01*
X554080Y-293843D02*
Y-289621D01*
X545920D02*
X554080D01*
X545920Y-293843D02*
Y-289621D01*
Y-293843D02*
X554080D01*
X590256Y-288440D02*
X593209D01*
X590256Y-294237D02*
Y-288440D01*
Y-294237D02*
X593209D01*
Y-288440D01*
X545965Y-256201D02*
X549705D01*
X545965Y-263090D02*
Y-256201D01*
Y-263090D02*
X549705D01*
Y-256201D01*
X577756Y-294685D02*
Y-288779D01*
X567126D02*
X577756D01*
X567126Y-294685D02*
Y-288779D01*
Y-294685D02*
X577756D01*
X590551Y-261233D02*
X598425D01*
Y-245854D01*
X590551D02*
X598425D01*
X590551Y-261233D02*
Y-245854D01*
X601575Y-261626D02*
X609449D01*
Y-246248D01*
X601575D02*
X609449D01*
X601575Y-261626D02*
Y-246248D01*
X655118Y-272441D02*
Y-264567D01*
Y-272441D02*
X673228D01*
Y-264567D01*
X655118D02*
X673228D01*
X644709Y-279528D02*
Y-276378D01*
X638756D02*
X644709D01*
X638756Y-279528D02*
Y-276378D01*
Y-279528D02*
X644709D01*
X660487Y-278489D02*
Y-274267D01*
Y-278489D02*
X668647D01*
Y-274267D01*
X660487D02*
X668647D01*
X661300Y-254414D02*
Y-250192D01*
Y-254414D02*
X669460D01*
Y-250192D01*
X661300D02*
X669460D01*
X660827Y-262598D02*
Y-257874D01*
Y-262598D02*
X669882D01*
Y-257874D01*
X660827D02*
X669882D01*
X627146Y-263779D02*
Y-244882D01*
Y-263779D02*
X659469D01*
Y-244882D01*
X627146D02*
X659469D01*
X675492Y-310827D02*
Y-289173D01*
X647342D02*
X675492D01*
X647342Y-310827D02*
Y-289173D01*
Y-310827D02*
X675492D01*
X640945Y-290354D02*
X645669D01*
X640945Y-299410D02*
Y-290354D01*
Y-299410D02*
X645669D01*
Y-290354D01*
X540354Y-112303D02*
X562008D01*
X540354Y-140453D02*
Y-112303D01*
Y-140453D02*
X562008D01*
Y-112303D01*
X539173Y-136221D02*
Y-131496D01*
X530118D02*
X539173D01*
X530118Y-136221D02*
Y-131496D01*
Y-136221D02*
X539173D01*
X495920Y-111319D02*
Y-108366D01*
Y-111319D02*
X501718D01*
Y-108366D01*
X495920D02*
X501718D01*
X476575Y-112795D02*
X501378D01*
X476575Y-132087D02*
Y-112795D01*
Y-132087D02*
X501378D01*
Y-112795D01*
X43996Y-45669D02*
X50492D01*
Y-33071D01*
X43996D02*
X50492D01*
X43996Y-45669D02*
Y-33071D01*
X121161Y-47244D02*
X127657D01*
Y-34646D01*
X121161D02*
X127657D01*
X121161Y-47244D02*
Y-34646D01*
X661417Y-59941D02*
Y-53445D01*
Y-59941D02*
X674016D01*
Y-53445D01*
X661417D02*
X674016D01*
X611811Y-57185D02*
Y-50689D01*
X599213D02*
X611811D01*
X599213Y-57185D02*
Y-50689D01*
Y-57185D02*
X611811D01*
X608681Y-181201D02*
Y-155807D01*
Y-181201D02*
X641713D01*
Y-155807D01*
X608681D02*
X641713D01*
X38189Y6890D02*
X42520D01*
Y16732D01*
X38189D02*
X42520D01*
X38189Y6890D02*
Y16732D01*
X31299Y6890D02*
X35630D01*
Y16732D01*
X31299D02*
X35630D01*
X31299Y6890D02*
Y16732D01*
X24409Y6890D02*
X28740D01*
Y16732D01*
X24409D02*
X28740D01*
X24409Y6890D02*
Y16732D01*
X45079Y6890D02*
X49409D01*
Y16732D01*
X45079D02*
X49409D01*
X45079Y6890D02*
Y16732D01*
X74410Y-112402D02*
Y-108071D01*
Y-112402D02*
X85433D01*
Y-108071D01*
X74410D02*
X85433D01*
X73425Y-120669D02*
X78150D01*
X73425Y-130118D02*
Y-120669D01*
Y-130118D02*
X78150D01*
Y-120669D01*
X663386Y-26870D02*
Y-20374D01*
Y-26870D02*
X675984D01*
Y-20374D01*
X663386D02*
X675984D01*
X619488Y-24754D02*
Y-18258D01*
X606890D02*
X619488D01*
X606890Y-24754D02*
Y-18258D01*
Y-24754D02*
X619488D01*
X86319Y-88041D02*
X92815D01*
X86319Y-100639D02*
Y-88041D01*
Y-100639D02*
X92815D01*
Y-88041D01*
X119783Y-69734D02*
X126279D01*
X119783Y-82332D02*
Y-69734D01*
Y-82332D02*
X126279D01*
Y-69734D01*
X508661Y-117765D02*
X522835D01*
Y-131939D02*
Y-117765D01*
X508661Y-131939D02*
X522835D01*
X508661D02*
Y-117765D01*
X454528Y-119201D02*
X466732D01*
X454528Y-132472D02*
Y-119201D01*
Y-132472D02*
X466732D01*
Y-119201D01*
M02*
